(kicad_pcb
	(version 20260206)
	(generator "pcbnew")
	(generator_version "10.0")
	(general
		(thickness 1.6)
		(legacy_teardrops no)
	)
	(paper "A4")
	(title_block
		(title "9052_F0T_PDB_Converter_Brick_F_V03_1208_1600_OCP.brd")
		(comment 1 "Grand Teton / footprints 17-24 of 578")
	)
	(layers
		(0 "F.Cu" signal "TOP")
		(4 "In1.Cu" signal "GND")
		(6 "In2.Cu" signal "IN1")
		(8 "In3.Cu" signal "GND1")
		(10 "In4.Cu" signal "VCC")
		(12 "In5.Cu" signal "VCC1")
		(14 "In6.Cu" signal "GND2")
		(16 "In7.Cu" signal "IN2")
		(18 "In8.Cu" signal "GND3")
		(2 "B.Cu" signal "BOTTOM")
		(9 "F.Adhes" user "F.Adhesive")
		(11 "B.Adhes" user "B.Adhesive")
		(13 "F.Paste" user "Package Geometry/Pastemask Top")
		(15 "B.Paste" user "Package Geometry/Pastemask Bottom")
		(5 "F.SilkS" user "Ref Des/Silkscreen Top")
		(7 "B.SilkS" user "Ref Des/Silkscreen Bottom")
		(1 "F.Mask" user "Board Geometry/Soldermask Top")
		(3 "B.Mask" user "Board Geometry/Soldermask Bottom")
		(17 "Dwgs.User" user "User.Drawings")
		(19 "Cmts.User" user "User.Comments")
		(21 "Eco1.User" user "User.Eco1")
		(23 "Eco2.User" user "User.Eco2")
		(25 "Edge.Cuts" user "Board Geometry/Outline")
		(27 "Margin" user)
		(31 "F.CrtYd" user "Package Geometry/Place Bound Top")
		(29 "B.CrtYd" user "Package Geometry/Place Bound Bottom")
		(35 "F.Fab" user "Ref Des/Assembly Top")
		(33 "B.Fab" user "Ref Des/Assembly Bottom")
	)
	(footprint ""
		(layer "F.Cu")
		(at 264.1854 -49.1998)
		(property "Reference" "PR24"
			(at 0 0 0)
			(layer "F.SilkS")
			(hide yes)
			(effects
				(font
					(size 1.27 1.27)
				)
			)
		)
		(property "Value" ""
			(at 0 0 0)
			(layer "F.Fab")
			(effects
				(font
					(size 1.27 1.27)
				)
			)
		)
		(duplicate_pad_numbers_are_jumpers no)
		(fp_line
			(start -0.7874 -0.4064)
			(end 0.7874 -0.4064)
			(stroke
				(width 0.1524)
				(type default)
			)
			(layer "F.SilkS")
		)
		(fp_line
			(start -0.7874 0.4064)
			(end -0.7874 -0.4064)
			(stroke
				(width 0.1524)
				(type default)
			)
			(layer "F.SilkS")
		)
		(fp_line
			(start 0.7874 -0.4064)
			(end 0.7874 0.4064)
			(stroke
				(width 0.1524)
				(type default)
			)
			(layer "F.SilkS")
		)
		(fp_line
			(start 0.7874 0.4064)
			(end -0.7874 0.4064)
			(stroke
				(width 0.1524)
				(type default)
			)
			(layer "F.SilkS")
		)
		(fp_line
			(start -0.67945 -0.305054)
			(end -0.12065 -0.305054)
			(stroke
				(width 0.1)
				(type default)
			)
			(layer "F.Fab")
		)
		(fp_line
			(start -0.67945 0.3048)
			(end -0.67945 -0.305054)
			(stroke
				(width 0.1)
				(type default)
			)
			(layer "F.Fab")
		)
		(fp_line
			(start -0.12065 -0.305054)
			(end -0.12065 -0.2794)
			(stroke
				(width 0.1)
				(type default)
			)
			(layer "F.Fab")
		)
		(fp_line
			(start -0.12065 -0.2794)
			(end 0.12065 -0.2794)
			(stroke
				(width 0.1)
				(type default)
			)
			(layer "F.Fab")
		)
		(fp_line
			(start -0.12065 0.2794)
			(end -0.12065 0.3048)
			(stroke
				(width 0.1)
				(type default)
			)
			(layer "F.Fab")
		)
		(fp_line
			(start -0.12065 0.3048)
			(end -0.67945 0.3048)
			(stroke
				(width 0.1)
				(type default)
			)
			(layer "F.Fab")
		)
		(fp_line
			(start 0.120396 0.2794)
			(end -0.12065 0.2794)
			(stroke
				(width 0.1)
				(type default)
			)
			(layer "F.Fab")
		)
		(fp_line
			(start 0.120396 0.3048)
			(end 0.120396 0.2794)
			(stroke
				(width 0.1)
				(type default)
			)
			(layer "F.Fab")
		)
		(fp_line
			(start 0.12065 -0.3048)
			(end 0.67945 -0.3048)
			(stroke
				(width 0.1)
				(type default)
			)
			(layer "F.Fab")
		)
		(fp_line
			(start 0.12065 -0.2794)
			(end 0.12065 -0.3048)
			(stroke
				(width 0.1)
				(type default)
			)
			(layer "F.Fab")
		)
		(fp_line
			(start 0.67945 -0.3048)
			(end 0.67945 0.3048)
			(stroke
				(width 0.1)
				(type default)
			)
			(layer "F.Fab")
		)
		(fp_line
			(start 0.67945 0.3048)
			(end 0.120396 0.3048)
			(stroke
				(width 0.1)
				(type default)
			)
			(layer "F.Fab")
		)
		(pad "1" smd circle
			(at -0.40005 0)
			(size 0 0)
			(layers "F.Cu" "F.Mask" "F.Paste")
			(net "P52V_HS1_FB")
		)
		(pad "2" smd circle
			(at 0.40005 0)
			(size 0 0)
			(layers "F.Cu" "F.Mask" "F.Paste")
			(net "GND_FIELD_SIGNAL")
		)
	)
	(footprint ""
		(layer "F.Cu")
		(at 106.426 -50.038)
		(property "Reference" "PC65"
			(at 0 0 0)
			(layer "F.SilkS")
			(hide yes)
			(effects
				(font
					(size 1.27 1.27)
				)
			)
		)
		(property "Value" ""
			(at 0 0 0)
			(layer "F.Fab")
			(effects
				(font
					(size 1.27 1.27)
				)
			)
		)
		(duplicate_pad_numbers_are_jumpers no)
		(fp_line
			(start -1.524 -0.762)
			(end 1.524 -0.762)
			(stroke
				(width 0.1524)
				(type default)
			)
			(layer "F.SilkS")
		)
		(fp_line
			(start -1.524 0.762)
			(end -1.524 -0.762)
			(stroke
				(width 0.1524)
				(type default)
			)
			(layer "F.SilkS")
		)
		(fp_line
			(start 1.524 -0.762)
			(end 1.524 0.762)
			(stroke
				(width 0.1524)
				(type default)
			)
			(layer "F.SilkS")
		)
		(fp_line
			(start 1.524 0.762)
			(end -1.524 0.762)
			(stroke
				(width 0.1524)
				(type default)
			)
			(layer "F.SilkS")
		)
		(fp_line
			(start -1.1049 -0.724916)
			(end -1.1049 0.724916)
			(stroke
				(width 0.1)
				(type default)
			)
			(layer "F.Fab")
		)
		(fp_line
			(start -1.1049 0.724916)
			(end 1.1049 0.724916)
			(stroke
				(width 0.1)
				(type default)
			)
			(layer "F.Fab")
		)
		(fp_line
			(start 1.1049 -0.724916)
			(end -1.1049 -0.724916)
			(stroke
				(width 0.1)
				(type default)
			)
			(layer "F.Fab")
		)
		(fp_line
			(start 1.1049 0.724916)
			(end 1.1049 -0.724916)
			(stroke
				(width 0.1)
				(type default)
			)
			(layer "F.Fab")
		)
		(pad "1" smd rect
			(at -0.889 0 180)
			(size 1.016 1.27)
			(layers "F.Cu" "F.Mask" "F.Paste")
			(net "P12V_BRICK")
		)
		(pad "2" smd rect
			(at 0.889 0 180)
			(size 1.016 1.27)
			(layers "F.Cu" "F.Mask" "F.Paste")
			(net "GND")
		)
	)
	(footprint ""
		(layer "F.Cu")
		(at 95.504 -50.038)
		(property "Reference" "PC87"
			(at 0 0 0)
			(layer "F.SilkS")
			(hide yes)
			(effects
				(font
					(size 1.27 1.27)
				)
			)
		)
		(property "Value" ""
			(at 0 0 0)
			(layer "F.Fab")
			(effects
				(font
					(size 1.27 1.27)
				)
			)
		)
		(duplicate_pad_numbers_are_jumpers no)
		(fp_line
			(start -1.524 -0.762)
			(end 1.524 -0.762)
			(stroke
				(width 0.1524)
				(type default)
			)
			(layer "F.SilkS")
		)
		(fp_line
			(start -1.524 0.762)
			(end -1.524 -0.762)
			(stroke
				(width 0.1524)
				(type default)
			)
			(layer "F.SilkS")
		)
		(fp_line
			(start 1.524 -0.762)
			(end 1.524 0.762)
			(stroke
				(width 0.1524)
				(type default)
			)
			(layer "F.SilkS")
		)
		(fp_line
			(start 1.524 0.762)
			(end -1.524 0.762)
			(stroke
				(width 0.1524)
				(type default)
			)
			(layer "F.SilkS")
		)
		(fp_line
			(start -1.1049 -0.724916)
			(end -1.1049 0.724916)
			(stroke
				(width 0.1)
				(type default)
			)
			(layer "F.Fab")
		)
		(fp_line
			(start -1.1049 0.724916)
			(end 1.1049 0.724916)
			(stroke
				(width 0.1)
				(type default)
			)
			(layer "F.Fab")
		)
		(fp_line
			(start 1.1049 -0.724916)
			(end -1.1049 -0.724916)
			(stroke
				(width 0.1)
				(type default)
			)
			(layer "F.Fab")
		)
		(fp_line
			(start 1.1049 0.724916)
			(end 1.1049 -0.724916)
			(stroke
				(width 0.1)
				(type default)
			)
			(layer "F.Fab")
		)
		(pad "1" smd rect
			(at -0.889 0 180)
			(size 1.016 1.27)
			(layers "F.Cu" "F.Mask" "F.Paste")
			(net "P12V_BRICK")
		)
		(pad "2" smd rect
			(at 0.889 0 180)
			(size 1.016 1.27)
			(layers "F.Cu" "F.Mask" "F.Paste")
			(net "GND")
		)
	)
	(footprint ""
		(layer "F.Cu")
		(at 201.257916 -66.956686 90)
		(property "Reference" "R61"
			(at 0 0 90)
			(layer "F.SilkS")
			(hide yes)
			(effects
				(font
					(size 1.27 1.27)
				)
			)
		)
		(property "Value" ""
			(at 0 0 90)
			(layer "F.Fab")
			(effects
				(font
					(size 1.27 1.27)
				)
			)
		)
		(duplicate_pad_numbers_are_jumpers no)
		(fp_line
			(start 0.7874 -0.4064)
			(end 0.7874 0.4064)
			(stroke
				(width 0.1524)
				(type default)
			)
			(layer "F.SilkS")
		)
		(fp_line
			(start -0.7874 -0.4064)
			(end 0.7874 -0.4064)
			(stroke
				(width 0.1524)
				(type default)
			)
			(layer "F.SilkS")
		)
		(fp_line
			(start 0.7874 0.4064)
			(end -0.7874 0.4064)
			(stroke
				(width 0.1524)
				(type default)
			)
			(layer "F.SilkS")
		)
		(fp_line
			(start -0.7874 0.4064)
			(end -0.7874 -0.4064)
			(stroke
				(width 0.1524)
				(type default)
			)
			(layer "F.SilkS")
		)
		(fp_line
			(start -0.12065 -0.305054)
			(end -0.12065 -0.2794)
			(stroke
				(width 0.1)
				(type default)
			)
			(layer "F.Fab")
		)
		(fp_line
			(start -0.67945 -0.305054)
			(end -0.12065 -0.305054)
			(stroke
				(width 0.1)
				(type default)
			)
			(layer "F.Fab")
		)
		(fp_line
			(start 0.67945 -0.3048)
			(end 0.67945 0.3048)
			(stroke
				(width 0.1)
				(type default)
			)
			(layer "F.Fab")
		)
		(fp_line
			(start 0.12065 -0.3048)
			(end 0.67945 -0.3048)
			(stroke
				(width 0.1)
				(type default)
			)
			(layer "F.Fab")
		)
		(fp_line
			(start 0.12065 -0.2794)
			(end 0.12065 -0.3048)
			(stroke
				(width 0.1)
				(type default)
			)
			(layer "F.Fab")
		)
		(fp_line
			(start -0.12065 -0.2794)
			(end 0.12065 -0.2794)
			(stroke
				(width 0.1)
				(type default)
			)
			(layer "F.Fab")
		)
		(fp_line
			(start 0.120396 0.2794)
			(end -0.12065 0.2794)
			(stroke
				(width 0.1)
				(type default)
			)
			(layer "F.Fab")
		)
		(fp_line
			(start -0.12065 0.2794)
			(end -0.12065 0.3048)
			(stroke
				(width 0.1)
				(type default)
			)
			(layer "F.Fab")
		)
		(fp_line
			(start 0.67945 0.3048)
			(end 0.120396 0.3048)
			(stroke
				(width 0.1)
				(type default)
			)
			(layer "F.Fab")
		)
		(fp_line
			(start 0.120396 0.3048)
			(end 0.120396 0.2794)
			(stroke
				(width 0.1)
				(type default)
			)
			(layer "F.Fab")
		)
		(fp_line
			(start -0.12065 0.3048)
			(end -0.67945 0.3048)
			(stroke
				(width 0.1)
				(type default)
			)
			(layer "F.Fab")
		)
		(fp_line
			(start -0.67945 0.3048)
			(end -0.67945 -0.305054)
			(stroke
				(width 0.1)
				(type default)
			)
			(layer "F.Fab")
		)
		(pad "1" smd circle
			(at -0.40005 0 90)
			(size 0 0)
			(layers "F.Cu" "F.Mask" "F.Paste")
			(net "LED_D2_R2")
		)
		(pad "2" smd circle
			(at 0.40005 0 90)
			(size 0 0)
			(layers "F.Cu" "F.Mask" "F.Paste")
			(net "LED_D2_R3")
		)
	)
	(footprint ""
		(layer "F.Cu")
		(at 274.2438 -24.2316)
		(property "Reference" "R5889"
			(at 0 0 0)
			(layer "F.SilkS")
			(hide yes)
			(effects
				(font
					(size 1.27 1.27)
				)
			)
		)
		(property "Value" ""
			(at 0 0 0)
			(layer "F.Fab")
			(effects
				(font
					(size 1.27 1.27)
				)
			)
		)
		(duplicate_pad_numbers_are_jumpers no)
		(fp_line
			(start -1.651 -0.8382)
			(end 1.651 -0.8382)
			(stroke
				(width 0.1524)
				(type default)
			)
			(layer "F.SilkS")
		)
		(fp_line
			(start -1.651 0.8382)
			(end -1.651 -0.8382)
			(stroke
				(width 0.1524)
				(type default)
			)
			(layer "F.SilkS")
		)
		(fp_line
			(start 1.651 -0.8382)
			(end 1.651 0.8382)
			(stroke
				(width 0.1524)
				(type default)
			)
			(layer "F.SilkS")
		)
		(fp_line
			(start 1.651 0.8382)
			(end -1.651 0.8382)
			(stroke
				(width 0.1524)
				(type default)
			)
			(layer "F.SilkS")
		)
		(fp_line
			(start -1.559814 -0.7366)
			(end -1.559814 0.7366)
			(stroke
				(width 0.1)
				(type default)
			)
			(layer "F.Fab")
		)
		(fp_line
			(start -1.559814 0.7366)
			(end -1.524 0.7366)
			(stroke
				(width 0.1)
				(type default)
			)
			(layer "F.Fab")
		)
		(fp_line
			(start -1.524 -0.7366)
			(end -1.559814 -0.7366)
			(stroke
				(width 0.1)
				(type default)
			)
			(layer "F.Fab")
		)
		(fp_line
			(start -1.524 0.7366)
			(end 1.524 0.7366)
			(stroke
				(width 0.1)
				(type default)
			)
			(layer "F.Fab")
		)
		(fp_line
			(start 1.524 -0.7366)
			(end -1.524 -0.7366)
			(stroke
				(width 0.1)
				(type default)
			)
			(layer "F.Fab")
		)
		(fp_line
			(start 1.524 0.7366)
			(end 1.560576 0.7366)
			(stroke
				(width 0.1)
				(type default)
			)
			(layer "F.Fab")
		)
		(fp_line
			(start 1.560576 -0.7366)
			(end 1.524 -0.7366)
			(stroke
				(width 0.1)
				(type default)
			)
			(layer "F.Fab")
		)
		(fp_line
			(start 1.560576 0.7366)
			(end 1.560576 -0.7366)
			(stroke
				(width 0.1)
				(type default)
			)
			(layer "F.Fab")
		)
		(pad "1" smd rect
			(at -0.94996 0 180)
			(size 1.1176 1.3716)
			(layers "F.Cu" "F.Mask" "F.Paste")
			(net "P52V_1_R")
		)
		(pad "2" smd rect
			(at 0.94996 0 180)
			(size 1.1176 1.3716)
			(layers "F.Cu" "F.Mask" "F.Paste")
			(net "P3V3_AND")
		)
	)
	(footprint ""
		(layer "F.Cu")
		(at 293.37 -50.673 -90)
		(property "Reference" "PR5"
			(at 0 0 270)
			(layer "F.SilkS")
			(hide yes)
			(effects
				(font
					(size 1.27 1.27)
				)
			)
		)
		(property "Value" ""
			(at 0 0 270)
			(layer "F.Fab")
			(effects
				(font
					(size 1.27 1.27)
				)
			)
		)
		(duplicate_pad_numbers_are_jumpers no)
		(fp_line
			(start -2.234946 0.9271)
			(end -2.234946 -0.9271)
			(stroke
				(width 0.1524)
				(type default)
			)
			(layer "F.SilkS")
		)
		(fp_line
			(start 2.234946 0.9271)
			(end -2.234946 0.9271)
			(stroke
				(width 0.1524)
				(type default)
			)
			(layer "F.SilkS")
		)
		(fp_line
			(start -2.234946 -0.9271)
			(end 2.234946 -0.9271)
			(stroke
				(width 0.1524)
				(type default)
			)
			(layer "F.SilkS")
		)
		(fp_line
			(start 2.234946 -0.9271)
			(end 2.234946 0.9271)
			(stroke
				(width 0.1524)
				(type default)
			)
			(layer "F.SilkS")
		)
		(fp_line
			(start -1.575054 0.824992)
			(end 1.575054 0.824992)
			(stroke
				(width 0.1)
				(type default)
			)
			(layer "F.Fab")
		)
		(fp_line
			(start 1.575054 0.824992)
			(end 1.575054 -0.824992)
			(stroke
				(width 0.1)
				(type default)
			)
			(layer "F.Fab")
		)
		(fp_line
			(start -1.575054 -0.824992)
			(end -1.575054 0.824992)
			(stroke
				(width 0.1)
				(type default)
			)
			(layer "F.Fab")
		)
		(fp_line
			(start 1.575054 -0.824992)
			(end -1.575054 -0.824992)
			(stroke
				(width 0.1)
				(type default)
			)
			(layer "F.Fab")
		)
		(pad "1" smd rect
			(at -1.599946 0 270)
			(size 1.016 1.6002)
			(layers "F.Cu" "F.Mask" "F.Paste")
			(net "P52V_1")
		)
		(pad "2" smd rect
			(at 1.599946 0 270)
			(size 1.016 1.6002)
			(layers "F.Cu" "F.Mask" "F.Paste")
			(net "P52V_HS1_VCC")
		)
	)
	(footprint ""
		(layer "F.Cu")
		(at 56.905906 -130.175)
		(property "Reference" "PC76"
			(at 0 0 0)
			(layer "F.SilkS")
			(hide yes)
			(effects
				(font
					(size 1.27 1.27)
				)
			)
		)
		(property "Value" ""
			(at 0 0 0)
			(layer "F.Fab")
			(effects
				(font
					(size 1.27 1.27)
				)
			)
		)
		(duplicate_pad_numbers_are_jumpers no)
		(fp_line
			(start -2.2098 -0.9398)
			(end 2.2098 -0.9398)
			(stroke
				(width 0.1524)
				(type default)
			)
			(layer "F.SilkS")
		)
		(fp_line
			(start -2.2098 0.9398)
			(end -2.2098 -0.9398)
			(stroke
				(width 0.1524)
				(type default)
			)
			(layer "F.SilkS")
		)
		(fp_line
			(start 2.2098 -0.9398)
			(end 2.2098 0.9398)
			(stroke
				(width 0.1524)
				(type default)
			)
			(layer "F.SilkS")
		)
		(fp_line
			(start 2.2098 0.9398)
			(end -2.2098 0.9398)
			(stroke
				(width 0.1524)
				(type default)
			)
			(layer "F.SilkS")
		)
		(fp_line
			(start -1.700022 -0.899922)
			(end 1.700022 -0.899922)
			(stroke
				(width 0.1)
				(type default)
			)
			(layer "F.Fab")
		)
		(fp_line
			(start -1.700022 0.899922)
			(end -1.700022 -0.899922)
			(stroke
				(width 0.1)
				(type default)
			)
			(layer "F.Fab")
		)
		(fp_line
			(start 1.700022 -0.899922)
			(end 1.700022 0.899922)
			(stroke
				(width 0.1)
				(type default)
			)
			(layer "F.Fab")
		)
		(fp_line
			(start 1.700022 0.899922)
			(end -1.700022 0.899922)
			(stroke
				(width 0.1)
				(type default)
			)
			(layer "F.Fab")
		)
		(pad "1" smd rect
			(at -1.4732 0 180)
			(size 1.1684 1.5748)
			(layers "F.Cu" "F.Mask" "F.Paste")
			(net "P52V_HS_FILTER")
		)
		(pad "2" smd rect
			(at 1.4732 0 180)
			(size 1.1684 1.5748)
			(layers "F.Cu" "F.Mask" "F.Paste")
			(net "GND")
		)
	)
	(footprint ""
		(layer "F.Cu")
		(at 270.383 -105.623868 -90)
		(property "Reference" "PR13"
			(at 0 0 270)
			(layer "F.SilkS")
			(hide yes)
			(effects
				(font
					(size 1.27 1.27)
				)
			)
		)
		(property "Value" ""
			(at 0 0 270)
			(layer "F.Fab")
			(effects
				(font
					(size 1.27 1.27)
				)
			)
		)
		(duplicate_pad_numbers_are_jumpers no)
		(fp_line
			(start -1.2954 0.5842)
			(end -1.2954 -0.5842)
			(stroke
				(width 0.1524)
				(type default)
			)
			(layer "F.SilkS")
		)
		(fp_line
			(start 1.2954 0.5842)
			(end -1.2954 0.5842)
			(stroke
				(width 0.1524)
				(type default)
			)
			(layer "F.SilkS")
		)
		(fp_line
			(start -1.2954 -0.5842)
			(end 1.2954 -0.5842)
			(stroke
				(width 0.1524)
				(type default)
			)
			(layer "F.SilkS")
		)
		(fp_line
			(start 1.2954 -0.5842)
			(end 1.2954 0.5842)
			(stroke
				(width 0.1524)
				(type default)
			)
			(layer "F.SilkS")
		)
		(fp_line
			(start -0.8636 0.4572)
			(end -0.8636 0.4318)
			(stroke
				(width 0.1)
				(type default)
			)
			(layer "F.Fab")
		)
		(fp_line
			(start 0.8636 0.4572)
			(end -0.8636 0.4572)
			(stroke
				(width 0.1)
				(type default)
			)
			(layer "F.Fab")
		)
		(fp_line
			(start -0.8636 0.4318)
			(end -0.8636 0.4064)
			(stroke
				(width 0.1)
				(type default)
			)
			(layer "F.Fab")
		)
		(fp_line
			(start -1.1938 0.4064)
			(end -1.1938 -0.406654)
			(stroke
				(width 0.1)
				(type default)
			)
			(layer "F.Fab")
		)
		(fp_line
			(start -0.8636 0.4064)
			(end -1.1938 0.4064)
			(stroke
				(width 0.1)
				(type default)
			)
			(layer "F.Fab")
		)
		(fp_line
			(start 0.8636 0.4064)
			(end 0.8636 0.4572)
			(stroke
				(width 0.1)
				(type default)
			)
			(layer "F.Fab")
		)
		(fp_line
			(start 1.1938 0.4064)
			(end 0.8636 0.4064)
			(stroke
				(width 0.1)
				(type default)
			)
			(layer "F.Fab")
		)
		(fp_line
			(start -1.1938 -0.406654)
			(end -0.8636 -0.406654)
			(stroke
				(width 0.1)
				(type default)
			)
			(layer "F.Fab")
		)
		(fp_line
			(start -0.8636 -0.406654)
			(end -0.8636 -0.4572)
			(stroke
				(width 0.1)
				(type default)
			)
			(layer "F.Fab")
		)
		(fp_line
			(start 0.8636 -0.406654)
			(end 1.1938 -0.406654)
			(stroke
				(width 0.1)
				(type default)
			)
			(layer "F.Fab")
		)
		(fp_line
			(start 1.1938 -0.406654)
			(end 1.1938 0.4064)
			(stroke
				(width 0.1)
				(type default)
			)
			(layer "F.Fab")
		)
		(fp_line
			(start -0.8636 -0.4572)
			(end 0.8636 -0.4572)
			(stroke
				(width 0.1)
				(type default)
			)
			(layer "F.Fab")
		)
		(fp_line
			(start 0.8636 -0.4572)
			(end 0.8636 -0.406654)
			(stroke
				(width 0.1)
				(type default)
			)
			(layer "F.Fab")
		)
		(pad "1" smd rect
			(at -0.7366 0 180)
			(size 0.7112 0.8128)
			(layers "F.Cu" "F.Mask" "F.Paste")
			(net "P52V_HS1_GATE1_R")
		)
		(pad "2" smd rect
			(at 0.7366 0 180)
			(size 0.7112 0.8128)
			(layers "F.Cu" "F.Mask" "F.Paste")
			(net "P52V_HS1_GATE3")
		)
	)
)
